(kicad_pcb
	(version 20260206)
	(generator "pcbnew")
	(generator_version "10.0")
	(general
		(thickness 1.6)
		(legacy_teardrops no)
	)
	(paper "A4")
	(title_block
		(title "04192023_DAF0TMB3IC0_F0TG_MB_C_brd_V02_OCP.brd")
		(comment 1 "Grand Teton / footprints 6124-6132 of 8354")
	)
	(layers
		(0 "F.Cu" signal "TOP")
		(4 "In1.Cu" signal "GND")
		(6 "In2.Cu" signal "IN1")
		(8 "In3.Cu" signal "GND1")
		(10 "In4.Cu" signal "IN2")
		(12 "In5.Cu" signal "GND2")
		(14 "In6.Cu" signal "IN3")
		(16 "In7.Cu" signal "GND3")
		(18 "In8.Cu" signal "VCC")
		(20 "In9.Cu" signal "VCC1")
		(22 "In10.Cu" signal "GND4")
		(24 "In11.Cu" signal "IN4")
		(26 "In12.Cu" signal "GND5")
		(28 "In13.Cu" signal "IN5")
		(30 "In14.Cu" signal "GND6")
		(32 "In15.Cu" signal "IN6")
		(34 "In16.Cu" signal "GND7")
		(2 "B.Cu" signal "BOTTOM")
		(9 "F.Adhes" user "F.Adhesive")
		(11 "B.Adhes" user "B.Adhesive")
		(13 "F.Paste" user "Package Geometry/Pastemask Top")
		(15 "B.Paste" user "Package Geometry/Pastemask Bottom")
		(5 "F.SilkS" user "Ref Des/Silkscreen Top")
		(7 "B.SilkS" user "Ref Des/Silkscreen Bottom")
		(1 "F.Mask" user "Board Geometry/Soldermask Top")
		(3 "B.Mask" user "Board Geometry/Soldermask Bottom")
		(17 "Dwgs.User" user "User.Drawings")
		(19 "Cmts.User" user "User.Comments")
		(21 "Eco1.User" user "User.Eco1")
		(23 "Eco2.User" user "User.Eco2")
		(25 "Edge.Cuts" user "Board Geometry/Outline")
		(27 "Margin" user)
		(31 "F.CrtYd" user "Package Geometry/Place Bound Top")
		(29 "B.CrtYd" user "Package Geometry/Place Bound Bottom")
		(35 "F.Fab" user "Ref Des/Assembly Top")
		(33 "B.Fab" user "Ref Des/Assembly Bottom")
	)
	(footprint ""
		(layer "B.Cu")
		(at 164.107368 -420.184834 90)
		(property "Reference" "R826"
			(at 0 0 90)
			(layer "B.SilkS")
			(hide yes)
			(effects
				(font
					(size 1.27 1.27)
				)
				(justify mirror)
			)
		)
		(property "Value" ""
			(at 0 0 90)
			(layer "B.Fab")
			(effects
				(font
					(size 1.27 1.27)
				)
				(justify mirror)
			)
		)
		(duplicate_pad_numbers_are_jumpers no)
		(fp_line
			(start 0.32512 -0.175006)
			(end -0.32512 -0.175006)
			(stroke
				(width 0.1)
				(type default)
			)
			(layer "B.Fab")
		)
		(fp_line
			(start -0.32512 -0.175006)
			(end -0.32512 0.175006)
			(stroke
				(width 0.1)
				(type default)
			)
			(layer "B.Fab")
		)
		(fp_line
			(start 0.32512 0.175006)
			(end 0.32512 -0.175006)
			(stroke
				(width 0.1)
				(type default)
			)
			(layer "B.Fab")
		)
		(fp_line
			(start -0.32512 0.175006)
			(end 0.32512 0.175006)
			(stroke
				(width 0.1)
				(type default)
			)
			(layer "B.Fab")
		)
		(pad "1" smd rect
			(at 0.2667 0 270)
			(size 0.3048 0.381)
			(layers "B.Cu" "B.Mask" "B.Paste")
			(net "P1V8_CPU1_RT_1D")
		)
		(pad "2" smd rect
			(at -0.2667 0 90)
			(size 0.3048 0.381)
			(layers "B.Cu" "B.Mask" "B.Paste")
			(net "SMB_RT_CPU1_P2_ROM_R_SDA")
		)
	)
	(footprint ""
		(layer "B.Cu")
		(at 304.023776 -194.88531 180)
		(property "Reference" "R7"
			(at 0 0 0)
			(layer "B.SilkS")
			(hide yes)
			(effects
				(font
					(size 1.27 1.27)
				)
				(justify mirror)
			)
		)
		(property "Value" ""
			(at 0 0 0)
			(layer "B.Fab")
			(effects
				(font
					(size 1.27 1.27)
				)
				(justify mirror)
			)
		)
		(duplicate_pad_numbers_are_jumpers no)
		(fp_line
			(start 0.7874 0.4064)
			(end 0.7874 -0.4064)
			(stroke
				(width 0.1524)
				(type default)
			)
			(layer "B.SilkS")
		)
		(fp_line
			(start 0.7874 -0.4064)
			(end -0.7874 -0.4064)
			(stroke
				(width 0.1524)
				(type default)
			)
			(layer "B.SilkS")
		)
		(fp_line
			(start -0.7874 0.4064)
			(end 0.7874 0.4064)
			(stroke
				(width 0.1524)
				(type default)
			)
			(layer "B.SilkS")
		)
		(fp_line
			(start -0.7874 -0.4064)
			(end -0.7874 0.4064)
			(stroke
				(width 0.1524)
				(type default)
			)
			(layer "B.SilkS")
		)
		(fp_line
			(start 0.67945 0.3048)
			(end 0.67945 -0.305054)
			(stroke
				(width 0.1)
				(type default)
			)
			(layer "B.Fab")
		)
		(fp_line
			(start 0.67945 -0.305054)
			(end 0.12065 -0.305054)
			(stroke
				(width 0.1)
				(type default)
			)
			(layer "B.Fab")
		)
		(fp_line
			(start 0.12065 0.3048)
			(end 0.67945 0.3048)
			(stroke
				(width 0.1)
				(type default)
			)
			(layer "B.Fab")
		)
		(fp_line
			(start 0.12065 0.2794)
			(end 0.12065 0.3048)
			(stroke
				(width 0.1)
				(type default)
			)
			(layer "B.Fab")
		)
		(fp_line
			(start 0.12065 -0.2794)
			(end -0.12065 -0.2794)
			(stroke
				(width 0.1)
				(type default)
			)
			(layer "B.Fab")
		)
		(fp_line
			(start 0.12065 -0.305054)
			(end 0.12065 -0.2794)
			(stroke
				(width 0.1)
				(type default)
			)
			(layer "B.Fab")
		)
		(fp_line
			(start -0.120396 0.3048)
			(end -0.120396 0.2794)
			(stroke
				(width 0.1)
				(type default)
			)
			(layer "B.Fab")
		)
		(fp_line
			(start -0.120396 0.2794)
			(end 0.12065 0.2794)
			(stroke
				(width 0.1)
				(type default)
			)
			(layer "B.Fab")
		)
		(fp_line
			(start -0.12065 -0.2794)
			(end -0.12065 -0.3048)
			(stroke
				(width 0.1)
				(type default)
			)
			(layer "B.Fab")
		)
		(fp_line
			(start -0.12065 -0.3048)
			(end -0.67945 -0.3048)
			(stroke
				(width 0.1)
				(type default)
			)
			(layer "B.Fab")
		)
		(fp_line
			(start -0.67945 0.3048)
			(end -0.120396 0.3048)
			(stroke
				(width 0.1)
				(type default)
			)
			(layer "B.Fab")
		)
		(fp_line
			(start -0.67945 -0.3048)
			(end -0.67945 0.3048)
			(stroke
				(width 0.1)
				(type default)
			)
			(layer "B.Fab")
		)
		(pad "1" smd circle
			(at 0.40005 0)
			(size 0 0)
			(layers "B.Cu" "B.Mask" "B.Paste")
			(net "PD_CHA_CPU0_DIMM0_SAA")
		)
		(pad "2" smd circle
			(at -0.40005 0)
			(size 0 0)
			(layers "B.Cu" "B.Mask" "B.Paste")
			(net "GND")
		)
	)
	(footprint ""
		(layer "B.Cu")
		(at 405.120856 -168.717468 -90)
		(property "Reference" "PC590_2"
			(at 0 0 90)
			(layer "B.SilkS")
			(hide yes)
			(effects
				(font
					(size 1.27 1.27)
				)
				(justify mirror)
			)
		)
		(property "Value" ""
			(at 0 0 90)
			(layer "B.Fab")
			(effects
				(font
					(size 1.27 1.27)
				)
				(justify mirror)
			)
		)
		(duplicate_pad_numbers_are_jumpers no)
		(fp_line
			(start -1.524 0.762)
			(end 1.524 0.762)
			(stroke
				(width 0.1524)
				(type default)
			)
			(layer "B.SilkS")
		)
		(fp_line
			(start 1.524 0.762)
			(end 1.524 -0.762)
			(stroke
				(width 0.1524)
				(type default)
			)
			(layer "B.SilkS")
		)
		(fp_line
			(start -1.524 -0.762)
			(end -1.524 0.762)
			(stroke
				(width 0.1524)
				(type default)
			)
			(layer "B.SilkS")
		)
		(fp_line
			(start 1.524 -0.762)
			(end -1.524 -0.762)
			(stroke
				(width 0.1524)
				(type default)
			)
			(layer "B.SilkS")
		)
		(fp_line
			(start -1.1049 0.724916)
			(end -1.1049 -0.724916)
			(stroke
				(width 0.1)
				(type default)
			)
			(layer "B.Fab")
		)
		(fp_line
			(start 1.1049 0.724916)
			(end -1.1049 0.724916)
			(stroke
				(width 0.1)
				(type default)
			)
			(layer "B.Fab")
		)
		(fp_line
			(start -1.1049 -0.724916)
			(end 1.1049 -0.724916)
			(stroke
				(width 0.1)
				(type default)
			)
			(layer "B.Fab")
		)
		(fp_line
			(start 1.1049 -0.724916)
			(end 1.1049 0.724916)
			(stroke
				(width 0.1)
				(type default)
			)
			(layer "B.Fab")
		)
		(pad "1" smd rect
			(at 0.889 0 270)
			(size 1.016 1.27)
			(layers "B.Cu" "B.Mask" "B.Paste")
			(net "SW_P12V_AUX_PVDDCR_SOC_P0_FLT")
		)
		(pad "2" smd rect
			(at -0.889 0 270)
			(size 1.016 1.27)
			(layers "B.Cu" "B.Mask" "B.Paste")
			(net "GND")
		)
	)
	(footprint ""
		(layer "B.Cu")
		(at 154.073606 -408.517344 90)
		(property "Reference" "C6749"
			(at 0 0 90)
			(layer "B.SilkS")
			(hide yes)
			(effects
				(font
					(size 1.27 1.27)
				)
				(justify mirror)
			)
		)
		(property "Value" ""
			(at 0 0 90)
			(layer "B.Fab")
			(effects
				(font
					(size 1.27 1.27)
				)
				(justify mirror)
			)
		)
		(duplicate_pad_numbers_are_jumpers no)
		(fp_line
			(start 0.299974 -0.150114)
			(end -0.299974 -0.150114)
			(stroke
				(width 0.1)
				(type default)
			)
			(layer "B.Fab")
		)
		(fp_line
			(start -0.299974 -0.150114)
			(end -0.299974 0.150114)
			(stroke
				(width 0.1)
				(type default)
			)
			(layer "B.Fab")
		)
		(fp_line
			(start 0.299974 0.150114)
			(end 0.299974 -0.150114)
			(stroke
				(width 0.1)
				(type default)
			)
			(layer "B.Fab")
		)
		(fp_line
			(start -0.299974 0.150114)
			(end 0.299974 0.150114)
			(stroke
				(width 0.1)
				(type default)
			)
			(layer "B.Fab")
		)
		(pad "1" smd rect
			(at 0.2667 0 270)
			(size 0.3048 0.381)
			(layers "B.Cu" "B.Mask" "B.Paste")
			(net "P5E_CPU1_P3_TX_BUF_C_DP<12>")
		)
		(pad "2" smd rect
			(at -0.2667 0 270)
			(size 0.3048 0.381)
			(layers "B.Cu" "B.Mask" "B.Paste")
			(net "P5E_CPU1_P3_TX_BUF_DP<12>")
		)
	)
	(footprint ""
		(layer "B.Cu")
		(at 65.193164 -17.227804)
		(property "Reference" "C1830"
			(at 0 0 0)
			(layer "B.SilkS")
			(hide yes)
			(effects
				(font
					(size 1.27 1.27)
				)
				(justify mirror)
			)
		)
		(property "Value" ""
			(at 0 0 0)
			(layer "B.Fab")
			(effects
				(font
					(size 1.27 1.27)
				)
				(justify mirror)
			)
		)
		(duplicate_pad_numbers_are_jumpers no)
		(fp_line
			(start -1.524 -0.762)
			(end -1.524 0.762)
			(stroke
				(width 0.1524)
				(type default)
			)
			(layer "B.SilkS")
		)
		(fp_line
			(start -1.524 0.762)
			(end 1.524 0.762)
			(stroke
				(width 0.1524)
				(type default)
			)
			(layer "B.SilkS")
		)
		(fp_line
			(start 1.524 -0.762)
			(end -1.524 -0.762)
			(stroke
				(width 0.1524)
				(type default)
			)
			(layer "B.SilkS")
		)
		(fp_line
			(start 1.524 0.762)
			(end 1.524 -0.762)
			(stroke
				(width 0.1524)
				(type default)
			)
			(layer "B.SilkS")
		)
		(fp_line
			(start -1.1049 -0.724916)
			(end 1.1049 -0.724916)
			(stroke
				(width 0.1)
				(type default)
			)
			(layer "B.Fab")
		)
		(fp_line
			(start -1.1049 0.724916)
			(end -1.1049 -0.724916)
			(stroke
				(width 0.1)
				(type default)
			)
			(layer "B.Fab")
		)
		(fp_line
			(start 1.1049 -0.724916)
			(end 1.1049 0.724916)
			(stroke
				(width 0.1)
				(type default)
			)
			(layer "B.Fab")
		)
		(fp_line
			(start 1.1049 0.724916)
			(end -1.1049 0.724916)
			(stroke
				(width 0.1)
				(type default)
			)
			(layer "B.Fab")
		)
		(pad "1" smd rect
			(at 0.889 0)
			(size 1.016 1.27)
			(layers "B.Cu" "B.Mask" "B.Paste")
			(net "P12V_OCP_V3_2_R")
		)
		(pad "2" smd rect
			(at -0.889 0)
			(size 1.016 1.27)
			(layers "B.Cu" "B.Mask" "B.Paste")
			(net "GND")
		)
	)
	(footprint ""
		(layer "B.Cu")
		(at 237.917482 -324.626986)
		(property "Reference" "R1231"
			(at 0 0 0)
			(layer "B.SilkS")
			(hide yes)
			(effects
				(font
					(size 1.27 1.27)
				)
				(justify mirror)
			)
		)
		(property "Value" ""
			(at 0 0 0)
			(layer "B.Fab")
			(effects
				(font
					(size 1.27 1.27)
				)
				(justify mirror)
			)
		)
		(duplicate_pad_numbers_are_jumpers no)
		(fp_line
			(start -0.7874 -0.4064)
			(end -0.7874 0.4064)
			(stroke
				(width 0.1524)
				(type default)
			)
			(layer "B.SilkS")
		)
		(fp_line
			(start -0.7874 0.4064)
			(end 0.7874 0.4064)
			(stroke
				(width 0.1524)
				(type default)
			)
			(layer "B.SilkS")
		)
		(fp_line
			(start 0.7874 -0.4064)
			(end -0.7874 -0.4064)
			(stroke
				(width 0.1524)
				(type default)
			)
			(layer "B.SilkS")
		)
		(fp_line
			(start 0.7874 0.4064)
			(end 0.7874 -0.4064)
			(stroke
				(width 0.1524)
				(type default)
			)
			(layer "B.SilkS")
		)
		(fp_line
			(start -0.67945 -0.3048)
			(end -0.67945 0.3048)
			(stroke
				(width 0.1)
				(type default)
			)
			(layer "B.Fab")
		)
		(fp_line
			(start -0.67945 0.3048)
			(end -0.120396 0.3048)
			(stroke
				(width 0.1)
				(type default)
			)
			(layer "B.Fab")
		)
		(fp_line
			(start -0.12065 -0.3048)
			(end -0.67945 -0.3048)
			(stroke
				(width 0.1)
				(type default)
			)
			(layer "B.Fab")
		)
		(fp_line
			(start -0.12065 -0.2794)
			(end -0.12065 -0.3048)
			(stroke
				(width 0.1)
				(type default)
			)
			(layer "B.Fab")
		)
		(fp_line
			(start -0.120396 0.2794)
			(end 0.12065 0.2794)
			(stroke
				(width 0.1)
				(type default)
			)
			(layer "B.Fab")
		)
		(fp_line
			(start -0.120396 0.3048)
			(end -0.120396 0.2794)
			(stroke
				(width 0.1)
				(type default)
			)
			(layer "B.Fab")
		)
		(fp_line
			(start 0.12065 -0.305054)
			(end 0.12065 -0.2794)
			(stroke
				(width 0.1)
				(type default)
			)
			(layer "B.Fab")
		)
		(fp_line
			(start 0.12065 -0.2794)
			(end -0.12065 -0.2794)
			(stroke
				(width 0.1)
				(type default)
			)
			(layer "B.Fab")
		)
		(fp_line
			(start 0.12065 0.2794)
			(end 0.12065 0.3048)
			(stroke
				(width 0.1)
				(type default)
			)
			(layer "B.Fab")
		)
		(fp_line
			(start 0.12065 0.3048)
			(end 0.67945 0.3048)
			(stroke
				(width 0.1)
				(type default)
			)
			(layer "B.Fab")
		)
		(fp_line
			(start 0.67945 -0.305054)
			(end 0.12065 -0.305054)
			(stroke
				(width 0.1)
				(type default)
			)
			(layer "B.Fab")
		)
		(fp_line
			(start 0.67945 0.3048)
			(end 0.67945 -0.305054)
			(stroke
				(width 0.1)
				(type default)
			)
			(layer "B.Fab")
		)
		(pad "1" smd circle
			(at 0.40005 0 180)
			(size 0 0)
			(layers "B.Cu" "B.Mask" "B.Paste")
			(net "P1V8_CPU0_RT_1D")
		)
		(pad "2" smd circle
			(at -0.40005 0 180)
			(size 0 0)
			(layers "B.Cu" "B.Mask" "B.Paste")
			(net "P1V8_CPU0_RT_1D_ADC")
		)
	)
	(footprint ""
		(layer "B.Cu")
		(at 197.94855 -195.8594 180)
		(property "Reference" "R1710"
			(at 0 0 0)
			(layer "B.SilkS")
			(hide yes)
			(effects
				(font
					(size 1.27 1.27)
				)
				(justify mirror)
			)
		)
		(property "Value" ""
			(at 0 0 0)
			(layer "B.Fab")
			(effects
				(font
					(size 1.27 1.27)
				)
				(justify mirror)
			)
		)
		(duplicate_pad_numbers_are_jumpers no)
		(fp_line
			(start 0.7874 0.4064)
			(end 0.7874 -0.4064)
			(stroke
				(width 0.1524)
				(type default)
			)
			(layer "B.SilkS")
		)
		(fp_line
			(start 0.7874 -0.4064)
			(end -0.7874 -0.4064)
			(stroke
				(width 0.1524)
				(type default)
			)
			(layer "B.SilkS")
		)
		(fp_line
			(start -0.7874 0.4064)
			(end 0.7874 0.4064)
			(stroke
				(width 0.1524)
				(type default)
			)
			(layer "B.SilkS")
		)
		(fp_line
			(start -0.7874 -0.4064)
			(end -0.7874 0.4064)
			(stroke
				(width 0.1524)
				(type default)
			)
			(layer "B.SilkS")
		)
		(fp_line
			(start 0.67945 0.3048)
			(end 0.67945 -0.305054)
			(stroke
				(width 0.1)
				(type default)
			)
			(layer "B.Fab")
		)
		(fp_line
			(start 0.67945 -0.305054)
			(end 0.12065 -0.305054)
			(stroke
				(width 0.1)
				(type default)
			)
			(layer "B.Fab")
		)
		(fp_line
			(start 0.12065 0.3048)
			(end 0.67945 0.3048)
			(stroke
				(width 0.1)
				(type default)
			)
			(layer "B.Fab")
		)
		(fp_line
			(start 0.12065 0.2794)
			(end 0.12065 0.3048)
			(stroke
				(width 0.1)
				(type default)
			)
			(layer "B.Fab")
		)
		(fp_line
			(start 0.12065 -0.2794)
			(end -0.12065 -0.2794)
			(stroke
				(width 0.1)
				(type default)
			)
			(layer "B.Fab")
		)
		(fp_line
			(start 0.12065 -0.305054)
			(end 0.12065 -0.2794)
			(stroke
				(width 0.1)
				(type default)
			)
			(layer "B.Fab")
		)
		(fp_line
			(start -0.120396 0.3048)
			(end -0.120396 0.2794)
			(stroke
				(width 0.1)
				(type default)
			)
			(layer "B.Fab")
		)
		(fp_line
			(start -0.120396 0.2794)
			(end 0.12065 0.2794)
			(stroke
				(width 0.1)
				(type default)
			)
			(layer "B.Fab")
		)
		(fp_line
			(start -0.12065 -0.2794)
			(end -0.12065 -0.3048)
			(stroke
				(width 0.1)
				(type default)
			)
			(layer "B.Fab")
		)
		(fp_line
			(start -0.12065 -0.3048)
			(end -0.67945 -0.3048)
			(stroke
				(width 0.1)
				(type default)
			)
			(layer "B.Fab")
		)
		(fp_line
			(start -0.67945 0.3048)
			(end -0.120396 0.3048)
			(stroke
				(width 0.1)
				(type default)
			)
			(layer "B.Fab")
		)
		(fp_line
			(start -0.67945 -0.3048)
			(end -0.67945 0.3048)
			(stroke
				(width 0.1)
				(type default)
			)
			(layer "B.Fab")
		)
		(pad "1" smd circle
			(at 0.40005 0)
			(size 0 0)
			(layers "B.Cu" "B.Mask" "B.Paste")
			(net "I3C_SPD_DDRGL_CPU1_SDA")
		)
		(pad "2" smd circle
			(at -0.40005 0)
			(size 0 0)
			(layers "B.Cu" "B.Mask" "B.Paste")
			(net "I3C_SPD_DDRK_CPU1_SDA")
		)
	)
	(footprint ""
		(layer "B.Cu")
		(at 327.823068 -335.055972 90)
		(property "Reference" "PC96_2"
			(at 0 0 90)
			(layer "B.SilkS")
			(hide yes)
			(effects
				(font
					(size 1.27 1.27)
				)
				(justify mirror)
			)
		)
		(property "Value" ""
			(at 0 0 90)
			(layer "B.Fab")
			(effects
				(font
					(size 1.27 1.27)
				)
				(justify mirror)
			)
		)
		(duplicate_pad_numbers_are_jumpers no)
		(fp_line
			(start 1.524 -0.762)
			(end -1.524 -0.762)
			(stroke
				(width 0.1524)
				(type default)
			)
			(layer "B.SilkS")
		)
		(fp_line
			(start -1.524 -0.762)
			(end -1.524 0.762)
			(stroke
				(width 0.1524)
				(type default)
			)
			(layer "B.SilkS")
		)
		(fp_line
			(start 1.524 0.762)
			(end 1.524 -0.762)
			(stroke
				(width 0.1524)
				(type default)
			)
			(layer "B.SilkS")
		)
		(fp_line
			(start -1.524 0.762)
			(end 1.524 0.762)
			(stroke
				(width 0.1524)
				(type default)
			)
			(layer "B.SilkS")
		)
		(fp_line
			(start 1.1049 -0.724916)
			(end 1.1049 0.724916)
			(stroke
				(width 0.1)
				(type default)
			)
			(layer "B.Fab")
		)
		(fp_line
			(start -1.1049 -0.724916)
			(end 1.1049 -0.724916)
			(stroke
				(width 0.1)
				(type default)
			)
			(layer "B.Fab")
		)
		(fp_line
			(start 1.1049 0.724916)
			(end -1.1049 0.724916)
			(stroke
				(width 0.1)
				(type default)
			)
			(layer "B.Fab")
		)
		(fp_line
			(start -1.1049 0.724916)
			(end -1.1049 -0.724916)
			(stroke
				(width 0.1)
				(type default)
			)
			(layer "B.Fab")
		)
		(pad "1" smd rect
			(at 0.889 0 90)
			(size 1.016 1.27)
			(layers "B.Cu" "B.Mask" "B.Paste")
			(net "SW_P12V_AUX_PVDDCR_CPU1_P0_FLT")
		)
		(pad "2" smd rect
			(at -0.889 0 90)
			(size 1.016 1.27)
			(layers "B.Cu" "B.Mask" "B.Paste")
			(net "GND")
		)
	)
	(footprint ""
		(layer "B.Cu")
		(at 406.095962 -416.899344 90)
		(property "Reference" "C6620"
			(at 0 0 90)
			(layer "B.SilkS")
			(hide yes)
			(effects
				(font
					(size 1.27 1.27)
				)
				(justify mirror)
			)
		)
		(property "Value" ""
			(at 0 0 90)
			(layer "B.Fab")
			(effects
				(font
					(size 1.27 1.27)
				)
				(justify mirror)
			)
		)
		(duplicate_pad_numbers_are_jumpers no)
		(fp_line
			(start 0.299974 -0.150114)
			(end -0.299974 -0.150114)
			(stroke
				(width 0.1)
				(type default)
			)
			(layer "B.Fab")
		)
		(fp_line
			(start -0.299974 -0.150114)
			(end -0.299974 0.150114)
			(stroke
				(width 0.1)
				(type default)
			)
			(layer "B.Fab")
		)
		(fp_line
			(start 0.299974 0.150114)
			(end 0.299974 -0.150114)
			(stroke
				(width 0.1)
				(type default)
			)
			(layer "B.Fab")
		)
		(fp_line
			(start -0.299974 0.150114)
			(end 0.299974 0.150114)
			(stroke
				(width 0.1)
				(type default)
			)
			(layer "B.Fab")
		)
		(pad "1" smd rect
			(at 0.2667 0 270)
			(size 0.3048 0.381)
			(layers "B.Cu" "B.Mask" "B.Paste")
			(net "P5E_CPU0_P3_TX_BUF_C_DN<11>")
		)
		(pad "2" smd rect
			(at -0.2667 0 270)
			(size 0.3048 0.381)
			(layers "B.Cu" "B.Mask" "B.Paste")
			(net "P5E_CPU0_P3_TX_BUF_DN<11>")
		)
	)
)
